FILE_TYPE = CONNECTIVITY;
{Allegro Design Entry HDL 17.2-2016 S081 (4005846) 1/11/2022}
"PAGE_NUMBER" = 273;
0"NC";
END.
